# BASEBOARD_FAB2 (Tioga Pass) — schematic netlist excerpt (pin names and nets, part order shuffled) for the footprints in the layout excerpt that follows; sources: Cadence DE-HDL packaged netlist, KiCad conversion of Wiwynn_Tioga_Pass_MB.brd

R2R11  RES  1.00K 1% EMPTY  pkg 0402  page 125 : A = SPI_PCH_IO2 ; B = GND
R25W102  RES  4.75K 1% EMPTY  pkg 0402  page 150 : A = P3V3_STBY ; B = BMC_STRAP_BIT18
R1E9  RES  1.00K 1% CHIP  pkg 0402  page 167 : A = P3V3_STBY ; B = PU_TMP421_2_A0

(kicad_pcb
	(version 20260206)
	(generator "pcbnew")
	(generator_version "10.0")
	(general
		(thickness 1.6)
		(legacy_teardrops no)
	)
	(paper "A4")
	(title_block
		(title "Wiwynn_Tioga_Pass_MB.brd")
		(comment 1 "Tioga Pass / footprints 2171-2173 of 4770")
	)
	(layers
		(0 "F.Cu" signal "TOP")
		(4 "In1.Cu" signal "L2GND")
		(6 "In2.Cu" signal "L3")
		(8 "In3.Cu" signal "L4GND")
		(10 "In4.Cu" signal "L5")
		(12 "In5.Cu" signal "L6GND")
		(14 "In6.Cu" signal "L7VCC")
		(16 "In7.Cu" signal "L8VCC")
		(18 "In8.Cu" signal "L9GND")
		(20 "In9.Cu" signal "L10")
		(22 "In10.Cu" signal "L11GND")
		(24 "In11.Cu" signal "L12")
		(26 "In12.Cu" signal "L13GND")
		(2 "B.Cu" signal "BOTTOM")
		(9 "F.Adhes" user "F.Adhesive")
		(11 "B.Adhes" user "B.Adhesive")
		(13 "F.Paste" user "Package Geometry/Pastemask Top")
		(15 "B.Paste" user "Package Geometry/Pastemask Bottom")
		(5 "F.SilkS" user "Ref Des/Silkscreen Top")
		(7 "B.SilkS" user "Ref Des/Silkscreen Bottom")
		(1 "F.Mask" user "Board Geometry/Soldermask Top")
		(3 "B.Mask" user "Board Geometry/Soldermask Bottom")
		(17 "Dwgs.User" user "User.Drawings")
		(19 "Cmts.User" user "User.Comments")
		(21 "Eco1.User" user "User.Eco1")
		(23 "Eco2.User" user "User.Eco2")
		(25 "Edge.Cuts" user "Board Geometry/Outline")
		(27 "Margin" user)
		(31 "F.CrtYd" user "Package Geometry/Place Bound Top")
		(29 "B.CrtYd" user "Package Geometry/Place Bound Bottom")
		(35 "F.Fab" user "Ref Des/Assembly Top")
		(33 "B.Fab" user "Ref Des/Assembly Bottom")
	)
	(footprint ""
		(layer "F.Cu")
		(at 374.015 -88.2015)
		(property "Reference" "R2R11"
			(at 0 0 0)
			(layer "F.SilkS")
			(hide yes)
			(effects
				(font
					(size 1.27 1.27)
				)
			)
		)
		(property "Value" ""
			(at 0 0 0)
			(layer "F.Fab")
			(effects
				(font
					(size 1.27 1.27)
				)
			)
		)
		(duplicate_pad_numbers_are_jumpers no)
		(fp_poly
			(pts
				(xy -0.2794 -0.1016) (xy 0.2794 -0.1016) (xy 0.2794 0.9906) (xy -0.2794 0.9906)
			)
			(stroke
				(width 0)
				(type default)
			)
			(fill no)
			(layer "F.CrtYd")
		)
		(fp_line
			(start -0.2794 -0.1016)
			(end -0.2794 0.9906)
			(stroke
				(width 0.1)
				(type default)
			)
			(layer "F.Fab")
		)
		(fp_line
			(start -0.2794 0.9906)
			(end 0.2794 0.9906)
			(stroke
				(width 0.1)
				(type default)
			)
			(layer "F.Fab")
		)
		(fp_line
			(start 0.2794 -0.1016)
			(end -0.2794 -0.1016)
			(stroke
				(width 0.1)
				(type default)
			)
			(layer "F.Fab")
		)
		(fp_line
			(start 0.2794 0.9906)
			(end 0.2794 -0.1016)
			(stroke
				(width 0.1)
				(type default)
			)
			(layer "F.Fab")
		)
		(pad "1" smd rect
			(at 0 0)
			(size 0.508 0.508)
			(layers "F.Cu" "F.Mask" "F.Paste")
			(net "SPI_PCH_IO2")
		)
		(pad "2" smd rect
			(at 0 0.889)
			(size 0.508 0.508)
			(layers "F.Cu" "F.Mask" "F.Paste")
			(net "GND")
		)
		(zone
			(layer "F.Cu")
			(hatch none 0.5)
			(connect_pads
				(clearance 0)
			)
			(min_thickness 0.25)
			(keepout
				(tracks allowed)
				(vias not_allowed)
				(pads allowed)
				(copperpour not_allowed)
				(footprints allowed)
			)
			(placement
				(enabled no)
				(sheetname "")
			)
			(fill
				(thermal_gap 0.5)
				(thermal_bridge_width 0.5)
				(island_removal_mode 0)
			)
			(polygon
				(pts
					(xy 373.761 -87.9475) (xy 374.269 -87.9475) (xy 374.269 -87.5665) (xy 373.761 -87.5665)
				)
			)
		)
		(zone
			(layer "F.Cu")
			(hatch none 0.5)
			(connect_pads
				(clearance 0)
			)
			(min_thickness 0.25)
			(keepout
				(tracks not_allowed)
				(vias allowed)
				(pads allowed)
				(copperpour not_allowed)
				(footprints allowed)
			)
			(placement
				(enabled no)
				(sheetname "")
			)
			(fill
				(thermal_gap 0.5)
				(thermal_bridge_width 0.5)
				(island_removal_mode 0)
			)
			(polygon
				(pts
					(xy 373.761 -87.5665) (xy 374.269 -87.5665) (xy 374.269 -87.9475) (xy 373.761 -87.9475)
				)
			)
		)
	)
	(footprint ""
		(layer "F.Cu")
		(at 2.794 -69.088 180)
		(property "Reference" "R1E9"
			(at 0 0 180)
			(layer "F.SilkS")
			(hide yes)
			(effects
				(font
					(size 1.27 1.27)
				)
			)
		)
		(property "Value" ""
			(at 0 0 180)
			(layer "F.Fab")
			(effects
				(font
					(size 1.27 1.27)
				)
			)
		)
		(duplicate_pad_numbers_are_jumpers no)
		(fp_poly
			(pts
				(xy -0.2794 -0.1016) (xy 0.2794 -0.1016) (xy 0.2794 0.9906) (xy -0.2794 0.9906)
			)
			(stroke
				(width 0)
				(type default)
			)
			(fill no)
			(layer "F.CrtYd")
		)
		(fp_line
			(start 0.2794 0.9906)
			(end 0.2794 -0.1016)
			(stroke
				(width 0.1)
				(type default)
			)
			(layer "F.Fab")
		)
		(fp_line
			(start 0.2794 -0.1016)
			(end -0.2794 -0.1016)
			(stroke
				(width 0.1)
				(type default)
			)
			(layer "F.Fab")
		)
		(fp_line
			(start -0.2794 0.9906)
			(end 0.2794 0.9906)
			(stroke
				(width 0.1)
				(type default)
			)
			(layer "F.Fab")
		)
		(fp_line
			(start -0.2794 -0.1016)
			(end -0.2794 0.9906)
			(stroke
				(width 0.1)
				(type default)
			)
			(layer "F.Fab")
		)
		(pad "1" smd rect
			(at 0 0 180)
			(size 0.508 0.508)
			(layers "F.Cu" "F.Mask" "F.Paste")
			(net "P3V3_STBY")
		)
		(pad "2" smd rect
			(at 0 0.889 180)
			(size 0.508 0.508)
			(layers "F.Cu" "F.Mask" "F.Paste")
			(net "PU_TMP421_2_A0")
		)
		(zone
			(layer "F.Cu")
			(hatch none 0.5)
			(connect_pads
				(clearance 0)
			)
			(min_thickness 0.25)
			(keepout
				(tracks not_allowed)
				(vias allowed)
				(pads allowed)
				(copperpour not_allowed)
				(footprints allowed)
			)
			(placement
				(enabled no)
				(sheetname "")
			)
			(fill
				(thermal_gap 0.5)
				(thermal_bridge_width 0.5)
				(island_removal_mode 0)
			)
			(polygon
				(pts
					(xy 3.048 -69.723) (xy 2.54 -69.723) (xy 2.54 -69.342) (xy 3.048 -69.342)
				)
			)
		)
		(zone
			(layer "F.Cu")
			(hatch none 0.5)
			(connect_pads
				(clearance 0)
			)
			(min_thickness 0.25)
			(keepout
				(tracks allowed)
				(vias not_allowed)
				(pads allowed)
				(copperpour not_allowed)
				(footprints allowed)
			)
			(placement
				(enabled no)
				(sheetname "")
			)
			(fill
				(thermal_gap 0.5)
				(thermal_bridge_width 0.5)
				(island_removal_mode 0)
			)
			(polygon
				(pts
					(xy 3.048 -69.342) (xy 2.54 -69.342) (xy 2.54 -69.723) (xy 3.048 -69.723)
				)
			)
		)
	)
	(footprint ""
		(layer "F.Cu")
		(at 422.744646 -48.968152)
		(property "Reference" "R25W102"
			(at -0.8382 -0.67818 0)
			(unlocked yes)
			(layer "F.SilkS")
			(effects
				(font
					(size 0.4064 0.254)
					(thickness 0.1524)
				)
				(justify left)
			)
		)
		(property "Value" ""
			(at 0 0 0)
			(layer "F.Fab")
			(effects
				(font
					(size 1.27 1.27)
				)
			)
		)
		(duplicate_pad_numbers_are_jumpers no)
		(fp_poly
			(pts
				(xy -0.2794 -0.1016) (xy 0.2794 -0.1016) (xy 0.2794 0.9906) (xy -0.2794 0.9906)
			)
			(stroke
				(width 0)
				(type default)
			)
			(fill no)
			(layer "F.CrtYd")
		)
		(fp_line
			(start -0.2794 -0.1016)
			(end -0.2794 0.9906)
			(stroke
				(width 0.1)
				(type default)
			)
			(layer "F.Fab")
		)
		(fp_line
			(start -0.2794 0.9906)
			(end 0.2794 0.9906)
			(stroke
				(width 0.1)
				(type default)
			)
			(layer "F.Fab")
		)
		(fp_line
			(start 0.2794 -0.1016)
			(end -0.2794 -0.1016)
			(stroke
				(width 0.1)
				(type default)
			)
			(layer "F.Fab")
		)
		(fp_line
			(start 0.2794 0.9906)
			(end 0.2794 -0.1016)
			(stroke
				(width 0.1)
				(type default)
			)
			(layer "F.Fab")
		)
		(pad "1" smd rect
			(at 0 0)
			(size 0.508 0.508)
			(layers "F.Cu" "F.Mask" "F.Paste")
			(net "P3V3_STBY")
		)
		(pad "2" smd rect
			(at 0 0.889)
			(size 0.508 0.508)
			(layers "F.Cu" "F.Mask" "F.Paste")
			(net "BMC_STRAP_BIT18")
		)
		(zone
			(layer "F.Cu")
			(hatch none 0.5)
			(connect_pads
				(clearance 0)
			)
			(min_thickness 0.25)
			(keepout
				(tracks allowed)
				(vias not_allowed)
				(pads allowed)
				(copperpour not_allowed)
				(footprints allowed)
			)
			(placement
				(enabled no)
				(sheetname "")
			)
			(fill
				(thermal_gap 0.5)
				(thermal_bridge_width 0.5)
				(island_removal_mode 0)
			)
			(polygon
				(pts
					(xy 422.490646 -48.714152) (xy 422.998646 -48.714152) (xy 422.998646 -48.333152) (xy 422.490646 -48.333152)
				)
			)
		)
		(zone
			(layer "F.Cu")
			(hatch none 0.5)
			(connect_pads
				(clearance 0)
			)
			(min_thickness 0.25)
			(keepout
				(tracks not_allowed)
				(vias allowed)
				(pads allowed)
				(copperpour not_allowed)
				(footprints allowed)
			)
			(placement
				(enabled no)
				(sheetname "")
			)
			(fill
				(thermal_gap 0.5)
				(thermal_bridge_width 0.5)
				(island_removal_mode 0)
			)
			(polygon
				(pts
					(xy 422.490646 -48.333152) (xy 422.998646 -48.333152) (xy 422.998646 -48.714152) (xy 422.490646 -48.714152)
				)
			)
		)
	)
)
